# TIMECARD (Time Appliance Project (Time Card)) — schematic netlist excerpt (pin names and nets, part order shuffled) for the footprints in the layout excerpt that follows; sources: Cadence DE-HDL packaged netlist, KiCad conversion of R4006-B0001-02_R01.brd

C124  CAPACITOR  0.1UF 10V 10%  pkg SMC_0402R_H022  page 14 : \1\ = XP1R0V_FPGA_MGTAVCC ; \2\ = SG
R69  RESISTOR  1KOHM 1%  pkg SMC_0402R_H016  page 18 : \1\ = SHT3X_ADDR ; \2\ = SG

(kicad_pcb
	(version 20260206)
	(generator "pcbnew")
	(generator_version "10.0")
	(general
		(thickness 1.6)
		(legacy_teardrops no)
	)
	(paper "A4")
	(title_block
		(title "timecard-production-celestica-r4006 — R4006-B0001-02_R01.brd")
		(comment 1 "Time Appliance Project (Time Card) / footprints 899-900 of 1113")
	)
	(layers
		(0 "F.Cu" signal "TOP")
		(4 "In1.Cu" signal "L02_GND1")
		(6 "In2.Cu" signal "L03_SIG1")
		(8 "In3.Cu" signal "L04_GND2")
		(10 "In4.Cu" signal "L05_VCC1")
		(12 "In5.Cu" signal "L06_VCC2")
		(14 "In6.Cu" signal "L07_GND3")
		(16 "In7.Cu" signal "L08_SIG2")
		(18 "In8.Cu" signal "L09_GND4")
		(2 "B.Cu" signal "BOTTOM")
		(9 "F.Adhes" user "F.Adhesive")
		(11 "B.Adhes" user "B.Adhesive")
		(13 "F.Paste" user "Package Geometry/Pastemask Top")
		(15 "B.Paste" user "Package Geometry/Pastemask Bottom")
		(5 "F.SilkS" user "Ref Des/Silkscreen Top")
		(7 "B.SilkS" user "Ref Des/Silkscreen Bottom")
		(1 "F.Mask" user "Board Geometry/Soldermask Top")
		(3 "B.Mask" user "Board Geometry/Soldermask Bottom")
		(17 "Dwgs.User" user "User.Drawings")
		(19 "Cmts.User" user "User.Comments")
		(21 "Eco1.User" user "User.Eco1")
		(23 "Eco2.User" user "User.Eco2")
		(25 "Edge.Cuts" user "Board Geometry/Outline")
		(27 "Margin" user)
		(31 "F.CrtYd" user "Package Geometry/Place Bound Top")
		(29 "B.CrtYd" user "Package Geometry/Place Bound Bottom")
		(35 "F.Fab" user "Ref Des/Assembly Top")
		(33 "B.Fab" user "Ref Des/Assembly Bottom")
	)
	(footprint ""
		(layer "B.Cu")
		(at 151.613108 -49.01311 90)
		(property "Reference" "R69"
			(at 3.81889 -1.030478 270)
			(unlocked yes)
			(layer "B.SilkS")
			(effects
				(font
					(size 0.7874 0.5842)
					(thickness 0.1524)
				)
				(justify mirror)
			)
		)
		(property "Value" "VAL*"
			(at -0.02032 2.13233 90)
			(unlocked yes)
			(layer "B.Fab")
			(hide yes)
			(effects
				(font
					(size 0.7874 0.5842)
					(thickness 0.1524)
				)
				(justify mirror)
			)
		)
		(property "Device Type" "RESISTOR-G155-11001-01,1KOHM,1%"
			(at -0.008382 1.210564 90)
			(unlocked yes)
			(layer "B.Fab")
			(hide yes)
			(effects
				(font
					(size 0.7874 0.5842)
					(thickness 0.1524)
				)
				(justify mirror)
			)
		)
		(property "User Part Number" "PARTNUM*"
			(at -0.02032 4.024884 90)
			(unlocked yes)
			(layer "Cmts.User")
			(hide yes)
			(effects
				(font
					(size 0.7874 0.5842)
					(thickness 0.1524)
				)
				(justify mirror)
			)
		)
		(property "Tolerance" "TOL*"
			(at -0.044704 3.05435 90)
			(unlocked yes)
			(layer "Cmts.User")
			(hide yes)
			(effects
				(font
					(size 0.7874 0.5842)
					(thickness 0.1524)
				)
				(justify mirror)
			)
		)
		(duplicate_pad_numbers_are_jumpers no)
		(fp_line
			(start 1.143 -0.5588)
			(end 1.143 0.5588)
			(stroke
				(width 0.1)
				(type default)
			)
			(layer "B.SilkS")
		)
		(fp_line
			(start -1.143 -0.5588)
			(end 1.143 -0.5588)
			(stroke
				(width 0.1)
				(type default)
			)
			(layer "B.SilkS")
		)
		(fp_line
			(start 1.143 0.5588)
			(end -1.143 0.5588)
			(stroke
				(width 0.1)
				(type default)
			)
			(layer "B.SilkS")
		)
		(fp_line
			(start -1.143 0.5588)
			(end -1.143 -0.5588)
			(stroke
				(width 0.1)
				(type default)
			)
			(layer "B.SilkS")
		)
		(fp_rect
			(start 1.143 0.5588)
			(end -1.143 -0.5588)
			(stroke
				(width 0)
				(type default)
			)
			(fill no)
			(layer "B.CrtYd")
		)
		(fp_line
			(start 0.508 -0.3048)
			(end 0.508 0.3048)
			(stroke
				(width 0.1)
				(type default)
			)
			(layer "B.Fab")
		)
		(fp_line
			(start -0.508 -0.3048)
			(end 0.508 -0.3048)
			(stroke
				(width 0.1)
				(type default)
			)
			(layer "B.Fab")
		)
		(fp_line
			(start 0.508 0.3048)
			(end -0.508 0.3048)
			(stroke
				(width 0.1)
				(type default)
			)
			(layer "B.Fab")
		)
		(fp_line
			(start -0.508 0.3048)
			(end -0.508 -0.3048)
			(stroke
				(width 0.1)
				(type default)
			)
			(layer "B.Fab")
		)
		(pad "1" smd rect
			(at 0.5334 0 270)
			(size 0.7112 0.6096)
			(layers "B.Cu" "B.Mask" "B.Paste")
			(net "SHT3X_ADDR")
		)
		(pad "2" smd rect
			(at -0.5334 0 270)
			(size 0.7112 0.6096)
			(layers "B.Cu" "B.Mask" "B.Paste")
			(net "SG")
		)
		(zone
			(layer "B.Cu")
			(hatch none 0.5)
			(connect_pads
				(clearance 0)
			)
			(min_thickness 0.25)
			(keepout
				(tracks allowed)
				(vias not_allowed)
				(pads allowed)
				(copperpour not_allowed)
				(footprints allowed)
			)
			(placement
				(enabled no)
				(sheetname "")
			)
			(fill
				(thermal_gap 0.5)
				(thermal_bridge_width 0.5)
				(island_removal_mode 0)
			)
			(polygon
				(pts
					(xy 151.917908 -49.08931) (xy 151.308308 -49.08931) (xy 151.308308 -48.93691) (xy 151.917908 -48.93691)
				)
			)
		)
	)
	(footprint ""
		(layer "B.Cu")
		(at 101.847142 -37.323014 90)
		(property "Reference" "C124"
			(at -1.524254 -42.018712 270)
			(unlocked yes)
			(layer "B.SilkS")
			(effects
				(font
					(size 0.635 0.4064)
					(thickness 0.1524)
				)
				(justify mirror)
			)
		)
		(property "Value" "VAL*"
			(at 0 3.718306 90)
			(unlocked yes)
			(layer "B.Fab")
			(hide yes)
			(effects
				(font
					(size 0.7874 0.5842)
					(thickness 0.127)
				)
				(justify mirror)
			)
		)
		(property "Tolerance" "TOL*"
			(at 0 4.861306 90)
			(unlocked yes)
			(layer "Cmts.User")
			(hide yes)
			(effects
				(font
					(size 0.7874 0.5842)
					(thickness 0.127)
				)
				(justify mirror)
			)
		)
		(property "User Part Number" "PARTNUM*"
			(at 0 2.575306 90)
			(unlocked yes)
			(layer "Cmts.User")
			(hide yes)
			(effects
				(font
					(size 0.7874 0.5842)
					(thickness 0.127)
				)
				(justify mirror)
			)
		)
		(property "Device Type" "CAPACITOR-G105-0B104-CK,0.1UF,A"
			(at 0 1.432306 90)
			(unlocked yes)
			(layer "B.Fab")
			(hide yes)
			(effects
				(font
					(size 0.7874 0.5842)
					(thickness 0.127)
				)
				(justify mirror)
			)
		)
		(duplicate_pad_numbers_are_jumpers no)
		(fp_line
			(start 0.970026 -0.4699)
			(end -0.970026 -0.4699)
			(stroke
				(width 0.1)
				(type default)
			)
			(layer "B.SilkS")
		)
		(fp_line
			(start -0.970026 -0.4699)
			(end -0.970026 0.4699)
			(stroke
				(width 0.1)
				(type default)
			)
			(layer "B.SilkS")
		)
		(fp_line
			(start 0.970026 0.4699)
			(end 0.970026 -0.4699)
			(stroke
				(width 0.1)
				(type default)
			)
			(layer "B.SilkS")
		)
		(fp_line
			(start -0.970026 0.4699)
			(end 0.970026 0.4699)
			(stroke
				(width 0.1)
				(type default)
			)
			(layer "B.SilkS")
		)
		(fp_poly
			(pts
				(xy 0.970026 0.4699) (xy -0.970026 0.4699) (xy -0.970026 -0.4699) (xy 0.970026 -0.4699)
			)
			(stroke
				(width 0)
				(type default)
			)
			(fill no)
			(layer "B.CrtYd")
		)
		(fp_line
			(start 0.508 -0.3048)
			(end -0.508 -0.3048)
			(stroke
				(width 0.1)
				(type default)
			)
			(layer "B.Fab")
		)
		(fp_line
			(start -0.508 -0.3048)
			(end -0.508 0.3048)
			(stroke
				(width 0.1)
				(type default)
			)
			(layer "B.Fab")
		)
		(fp_line
			(start 0.508 0.3048)
			(end 0.508 -0.3048)
			(stroke
				(width 0.1)
				(type default)
			)
			(layer "B.Fab")
		)
		(fp_line
			(start -0.508 0.3048)
			(end 0.508 0.3048)
			(stroke
				(width 0.1)
				(type default)
			)
			(layer "B.Fab")
		)
		(pad "1" smd circle
			(at 0.500126 0 270)
			(size 0.635 0.635)
			(layers "B.Cu" "B.Mask" "B.Paste")
			(net "XP1R0V_FPGA_MGTAVCC")
		)
		(pad "2" smd circle
			(at -0.500126 0 270)
			(size 0.635 0.635)
			(layers "B.Cu" "B.Mask" "B.Paste")
			(net "SG")
		)
	)
)
